(kicad_pcb
	(version 20260206)
	(generator "pcbnew")
	(generator_version "10.0")
	(general
		(thickness 1.6)
		(legacy_teardrops no)
	)
	(paper "A4")
	(title_block
		(title "04192023_DAF0TMB3IC0_F0TG_MB_C_brd_V02_OCP.brd")
		(comment 1 "Grand Teton / footprint 1180 of 8354 (J59), pads 1-71 of 71")
	)
	(layers
		(0 "F.Cu" signal "TOP")
		(4 "In1.Cu" signal "GND")
		(6 "In2.Cu" signal "IN1")
		(8 "In3.Cu" signal "GND1")
		(10 "In4.Cu" signal "IN2")
		(12 "In5.Cu" signal "GND2")
		(14 "In6.Cu" signal "IN3")
		(16 "In7.Cu" signal "GND3")
		(18 "In8.Cu" signal "VCC")
		(20 "In9.Cu" signal "VCC1")
		(22 "In10.Cu" signal "GND4")
		(24 "In11.Cu" signal "IN4")
		(26 "In12.Cu" signal "GND5")
		(28 "In13.Cu" signal "IN5")
		(30 "In14.Cu" signal "GND6")
		(32 "In15.Cu" signal "IN6")
		(34 "In16.Cu" signal "GND7")
		(2 "B.Cu" signal "BOTTOM")
		(9 "F.Adhes" user "F.Adhesive")
		(11 "B.Adhes" user "B.Adhesive")
		(13 "F.Paste" user "Package Geometry/Pastemask Top")
		(15 "B.Paste" user "Package Geometry/Pastemask Bottom")
		(5 "F.SilkS" user "Ref Des/Silkscreen Top")
		(7 "B.SilkS" user "Ref Des/Silkscreen Bottom")
		(1 "F.Mask" user "Board Geometry/Soldermask Top")
		(3 "B.Mask" user "Board Geometry/Soldermask Bottom")
		(17 "Dwgs.User" user "User.Drawings")
		(19 "Cmts.User" user "User.Comments")
		(21 "Eco1.User" user "User.Eco1")
		(23 "Eco2.User" user "User.Eco2")
		(25 "Edge.Cuts" user "Board Geometry/Outline")
		(27 "Margin" user)
		(31 "F.CrtYd" user "Package Geometry/Place Bound Top")
		(29 "B.CrtYd" user "Package Geometry/Place Bound Bottom")
		(35 "F.Fab" user "Ref Des/Assembly Top")
		(33 "B.Fab" user "Ref Des/Assembly Bottom")
	)
	(footprint ""
		(layer "F.Cu")
		(at 173.358302 -47.049944)
		(property "Reference" "J59"
			(at -4.4958 -11.852148 0)
			(unlocked yes)
			(layer "F.SilkS")
			(effects
				(font
					(size 0.7874 0.5842)
					(thickness 0.1524)
				)
				(justify left)
			)
		)
		(property "Value" ""
			(at 0 0 0)
			(layer "F.Fab")
			(effects
				(font
					(size 1.27 1.27)
				)
			)
		)
		(duplicate_pad_numbers_are_jumpers no)
		(pad "" np_thru_hole circle
			(at -1.525016 -9.99998 270)
			(size 1.1684 1.1684)
			(drill 1.1684)
			(layers "*.Cu" "*.Mask")
			(clearance 0.381)
			(thermal_gap 0.381)
		)
		(pad "" np_thru_hole circle
			(at -1.525016 9.99998 270)
			(size 1.651 1.651)
			(drill 1.651)
			(layers "*.Cu" "*.Mask")
			(clearance 0.381)
			(thermal_gap 0.381)
		)
		(pad "1" smd rect
			(at 3.750056 -9.249918 270)
			(size 0.2794 1.6002)
			(layers "F.Cu" "F.Mask" "F.Paste")
			(net "PCIE_M2_SSD0_PRSNT_N")
		)
		(pad "2" smd rect
			(at -3.800094 -8.999982 270)
			(size 0.2794 1.6002)
			(layers "F.Cu" "F.Mask" "F.Paste")
			(net "P3V3_M2_0")
		)
		(pad "3" smd rect
			(at 3.750056 -8.750046 270)
			(size 0.2794 1.6002)
			(layers "F.Cu" "F.Mask" "F.Paste")
			(net "GND")
		)
		(pad "4" smd rect
			(at -3.800094 -8.50011 270)
			(size 0.2794 1.6002)
			(layers "F.Cu" "F.Mask" "F.Paste")
			(net "P3V3_M2_0")
		)
		(pad "5" smd rect
			(at 3.750056 -8.24992 270)
			(size 0.2794 1.6002)
			(layers "F.Cu" "F.Mask" "F.Paste")
			(net "P3E_CPU1_P4_RX_DN<3>")
		)
		(pad "6" smd rect
			(at -3.800094 -7.999984 270)
			(size 0.2794 1.6002)
			(layers "F.Cu" "F.Mask" "F.Paste")
			(net "NC_M2_0_NC1")
		)
		(pad "7" smd rect
			(at 3.750056 -7.750048 270)
			(size 0.2794 1.6002)
			(layers "F.Cu" "F.Mask" "F.Paste")
			(net "P3E_CPU1_P4_RX_DP<3>")
		)
		(pad "8" smd rect
			(at -3.800094 -7.500112 270)
			(size 0.2794 1.6002)
			(layers "F.Cu" "F.Mask" "F.Paste")
			(net "NC_M2_0_NC2")
		)
		(pad "9" smd rect
			(at 3.750056 -7.249922 270)
			(size 0.2794 1.6002)
			(layers "F.Cu" "F.Mask" "F.Paste")
			(net "GND")
		)
		(pad "10" smd rect
			(at -3.800094 -6.999986 270)
			(size 0.2794 1.6002)
			(layers "F.Cu" "F.Mask" "F.Paste")
			(net "LED_M2_SSD_0_ACT_N")
		)
		(pad "11" smd rect
			(at 3.750056 -6.75005 270)
			(size 0.2794 1.6002)
			(layers "F.Cu" "F.Mask" "F.Paste")
			(net "P3E_CPU1_P4_TX_C_DN<3>")
		)
		(pad "12" smd rect
			(at -3.800094 -6.500114 270)
			(size 0.2794 1.6002)
			(layers "F.Cu" "F.Mask" "F.Paste")
			(net "P3V3_M2_0")
		)
		(pad "13" smd rect
			(at 3.750056 -6.249924 270)
			(size 0.2794 1.6002)
			(layers "F.Cu" "F.Mask" "F.Paste")
			(net "P3E_CPU1_P4_TX_C_DP<3>")
		)
		(pad "14" smd rect
			(at -3.800094 -5.999988 270)
			(size 0.2794 1.6002)
			(layers "F.Cu" "F.Mask" "F.Paste")
			(net "P3V3_M2_0")
		)
		(pad "15" smd rect
			(at 3.750056 -5.750052 270)
			(size 0.2794 1.6002)
			(layers "F.Cu" "F.Mask" "F.Paste")
			(net "GND")
		)
		(pad "16" smd rect
			(at -3.800094 -5.500116 270)
			(size 0.2794 1.6002)
			(layers "F.Cu" "F.Mask" "F.Paste")
			(net "P3V3_M2_0")
		)
		(pad "17" smd rect
			(at 3.750056 -5.249926 270)
			(size 0.2794 1.6002)
			(layers "F.Cu" "F.Mask" "F.Paste")
			(net "P3E_CPU1_P4_RX_DN<2>")
		)
		(pad "18" smd rect
			(at -3.800094 -4.99999 270)
			(size 0.2794 1.6002)
			(layers "F.Cu" "F.Mask" "F.Paste")
			(net "P3V3_M2_0")
		)
		(pad "19" smd rect
			(at 3.750056 -4.750054 270)
			(size 0.2794 1.6002)
			(layers "F.Cu" "F.Mask" "F.Paste")
			(net "P3E_CPU1_P4_RX_DP<2>")
		)
		(pad "20" smd rect
			(at -3.800094 -4.500118 270)
			(size 0.2794 1.6002)
			(layers "F.Cu" "F.Mask" "F.Paste")
			(net "NC_M2_0_NC3")
		)
		(pad "21" smd rect
			(at 3.750056 -4.249928 270)
			(size 0.2794 1.6002)
			(layers "F.Cu" "F.Mask" "F.Paste")
			(net "GND")
		)
		(pad "22" smd rect
			(at -3.800094 -3.999992 270)
			(size 0.2794 1.6002)
			(layers "F.Cu" "F.Mask" "F.Paste")
			(net "NC_M2_0_NC4")
		)
		(pad "23" smd rect
			(at 3.750056 -3.750056 270)
			(size 0.2794 1.6002)
			(layers "F.Cu" "F.Mask" "F.Paste")
			(net "P3E_CPU1_P4_TX_C_DN<2>")
		)
		(pad "24" smd rect
			(at -3.800094 -3.50012 270)
			(size 0.2794 1.6002)
			(layers "F.Cu" "F.Mask" "F.Paste")
			(net "NC_M2_0_NC5")
		)
		(pad "25" smd rect
			(at 3.750056 -3.24993 270)
			(size 0.2794 1.6002)
			(layers "F.Cu" "F.Mask" "F.Paste")
			(net "P3E_CPU1_P4_TX_C_DP<2>")
		)
		(pad "26" smd rect
			(at -3.800094 -2.999994 270)
			(size 0.2794 1.6002)
			(layers "F.Cu" "F.Mask" "F.Paste")
			(net "NC_M2_0_NC6")
		)
		(pad "27" smd rect
			(at 3.750056 -2.750058 270)
			(size 0.2794 1.6002)
			(layers "F.Cu" "F.Mask" "F.Paste")
			(net "GND")
		)
		(pad "28" smd rect
			(at -3.800094 -2.500122 270)
			(size 0.2794 1.6002)
			(layers "F.Cu" "F.Mask" "F.Paste")
			(net "NC_M2_0_NC7")
		)
		(pad "29" smd rect
			(at 3.750056 -2.249932 270)
			(size 0.2794 1.6002)
			(layers "F.Cu" "F.Mask" "F.Paste")
			(net "P3E_CPU1_P4_RX_DN<1>")
		)
		(pad "30" smd rect
			(at -3.800094 -1.999996 270)
			(size 0.2794 1.6002)
			(layers "F.Cu" "F.Mask" "F.Paste")
			(net "NC_M2_0_NC8")
		)
		(pad "31" smd rect
			(at 3.750056 -1.75006 270)
			(size 0.2794 1.6002)
			(layers "F.Cu" "F.Mask" "F.Paste")
			(net "P3E_CPU1_P4_RX_DP<1>")
		)
		(pad "32" smd rect
			(at -3.800094 -1.500124 270)
			(size 0.2794 1.6002)
			(layers "F.Cu" "F.Mask" "F.Paste")
			(net "NC_M2_0_NC9")
		)
		(pad "33" smd rect
			(at 3.750056 -1.249934 270)
			(size 0.2794 1.6002)
			(layers "F.Cu" "F.Mask" "F.Paste")
			(net "GND")
		)
		(pad "34" smd rect
			(at -3.800094 -0.999998 270)
			(size 0.2794 1.6002)
			(layers "F.Cu" "F.Mask" "F.Paste")
			(net "NC_M2_0_NC10")
		)
		(pad "35" smd rect
			(at 3.750056 -0.750062 270)
			(size 0.2794 1.6002)
			(layers "F.Cu" "F.Mask" "F.Paste")
			(net "P3E_CPU1_P4_TX_C_DN<1>")
		)
		(pad "36" smd rect
			(at -3.800094 -0.499872 270)
			(size 0.2794 1.6002)
			(layers "F.Cu" "F.Mask" "F.Paste")
			(net "NC_M2_0_NC11")
		)
		(pad "37" smd rect
			(at 3.750056 -0.249936 270)
			(size 0.2794 1.6002)
			(layers "F.Cu" "F.Mask" "F.Paste")
			(net "P3E_CPU1_P4_TX_C_DP<1>")
		)
		(pad "38" smd rect
			(at -3.800094 0 270)
			(size 0.2794 1.6002)
			(layers "F.Cu" "F.Mask" "F.Paste")
			(net "PD_M2_0_DEVSLP")
		)
		(pad "39" smd rect
			(at 3.750056 0.249936 270)
			(size 0.2794 1.6002)
			(layers "F.Cu" "F.Mask" "F.Paste")
			(net "GND")
		)
		(pad "40" smd rect
			(at -3.800094 0.499872 270)
			(size 0.2794 1.6002)
			(layers "F.Cu" "F.Mask" "F.Paste")
			(net "SMB_M2_P1_1V8AUX_SCL")
		)
		(pad "41" smd rect
			(at 3.750056 0.750062 270)
			(size 0.2794 1.6002)
			(layers "F.Cu" "F.Mask" "F.Paste")
			(net "P3E_CPU1_P4_RX_DN<0>")
		)
		(pad "42" smd rect
			(at -3.800094 0.999998 270)
			(size 0.2794 1.6002)
			(layers "F.Cu" "F.Mask" "F.Paste")
			(net "SMB_M2_P1_1V8AUX_SDA")
		)
		(pad "43" smd rect
			(at 3.750056 1.249934 270)
			(size 0.2794 1.6002)
			(layers "F.Cu" "F.Mask" "F.Paste")
			(net "P3E_CPU1_P4_RX_DP<0>")
		)
		(pad "44" smd rect
			(at -3.800094 1.500124 270)
			(size 0.2794 1.6002)
			(layers "F.Cu" "F.Mask" "F.Paste")
			(net "NC_M2_0_NC14")
		)
		(pad "45" smd rect
			(at 3.750056 1.75006 270)
			(size 0.2794 1.6002)
			(layers "F.Cu" "F.Mask" "F.Paste")
			(net "GND")
		)
		(pad "46" smd rect
			(at -3.800094 1.999996 270)
			(size 0.2794 1.6002)
			(layers "F.Cu" "F.Mask" "F.Paste")
			(net "NC_M2_0_NC15")
		)
		(pad "47" smd rect
			(at 3.750056 2.249932 270)
			(size 0.2794 1.6002)
			(layers "F.Cu" "F.Mask" "F.Paste")
			(net "P3E_CPU1_P4_TX_C_DN<0>")
		)
		(pad "48" smd rect
			(at -3.800094 2.500122 270)
			(size 0.2794 1.6002)
			(layers "F.Cu" "F.Mask" "F.Paste")
			(net "NC_M2_0_NC16")
		)
		(pad "49" smd rect
			(at 3.750056 2.750058 270)
			(size 0.2794 1.6002)
			(layers "F.Cu" "F.Mask" "F.Paste")
			(net "P3E_CPU1_P4_TX_C_DP<0>")
		)
		(pad "50" smd rect
			(at -3.800094 2.999994 270)
			(size 0.2794 1.6002)
			(layers "F.Cu" "F.Mask" "F.Paste")
			(net "RST_PERST_BUF_M2_0_R_N")
		)
		(pad "51" smd rect
			(at 3.750056 3.24993 270)
			(size 0.2794 1.6002)
			(layers "F.Cu" "F.Mask" "F.Paste")
			(net "GND")
		)
		(pad "52" smd rect
			(at -3.800094 3.50012 270)
			(size 0.2794 1.6002)
			(layers "F.Cu" "F.Mask" "F.Paste")
			(net "M2_SSD0_CLKREQ_EN_N_BUF")
		)
		(pad "53" smd rect
			(at 3.750056 3.750056 270)
			(size 0.2794 1.6002)
			(layers "F.Cu" "F.Mask" "F.Paste")
			(net "CLK_100M_CPU1_CLK12_DN")
		)
		(pad "54" smd rect
			(at -3.800094 3.999992 270)
			(size 0.2794 1.6002)
			(layers "F.Cu" "F.Mask" "F.Paste")
			(net "M2_0_PEWAKE_N")
		)
		(pad "55" smd rect
			(at 3.750056 4.249928 270)
			(size 0.2794 1.6002)
			(layers "F.Cu" "F.Mask" "F.Paste")
			(net "CLK_100M_CPU1_CLK12_DP")
		)
		(pad "56" smd rect
			(at -3.800094 4.500118 270)
			(size 0.2794 1.6002)
			(layers "F.Cu" "F.Mask" "F.Paste")
			(net "NC_M2_0_NC17")
		)
		(pad "57" smd rect
			(at 3.750056 4.750054 270)
			(size 0.2794 1.6002)
			(layers "F.Cu" "F.Mask" "F.Paste")
			(net "GND")
		)
		(pad "58" smd rect
			(at -3.800094 4.99999 270)
			(size 0.2794 1.6002)
			(layers "F.Cu" "F.Mask" "F.Paste")
			(net "NC_M2_0_NC18")
		)
		(pad "67" smd rect
			(at 3.750056 7.249922 270)
			(size 0.2794 1.6002)
			(layers "F.Cu" "F.Mask" "F.Paste")
			(net "NC_M2_0_NC19")
		)
		(pad "68" smd rect
			(at -3.800094 7.500112 270)
			(size 0.2794 1.6002)
			(layers "F.Cu" "F.Mask" "F.Paste")
			(net "NC_M2_0_SUSCLK")
		)
		(pad "69" smd rect
			(at 3.750056 7.750048 270)
			(size 0.2794 1.6002)
			(layers "F.Cu" "F.Mask" "F.Paste")
			(net "FM_M2_SSD_0_PEDET")
		)
		(pad "70" smd rect
			(at -3.800094 7.999984 270)
			(size 0.2794 1.6002)
			(layers "F.Cu" "F.Mask" "F.Paste")
			(net "P3V3_M2_0")
		)
		(pad "71" smd rect
			(at 3.750056 8.24992 270)
			(size 0.2794 1.6002)
			(layers "F.Cu" "F.Mask" "F.Paste")
			(net "GND")
		)
		(pad "72" smd rect
			(at -3.800094 8.50011 270)
			(size 0.2794 1.6002)
			(layers "F.Cu" "F.Mask" "F.Paste")
			(net "P3V3_M2_0")
		)
		(pad "73" smd rect
			(at 3.750056 8.750046 270)
			(size 0.2794 1.6002)
			(layers "F.Cu" "F.Mask" "F.Paste")
			(net "GND")
		)
		(pad "74" smd rect
			(at -3.800094 8.999982 270)
			(size 0.2794 1.6002)
			(layers "F.Cu" "F.Mask" "F.Paste")
			(net "P3V3_M2_0")
		)
		(pad "75" smd rect
			(at 3.750056 9.249918 270)
			(size 0.2794 1.6002)
			(layers "F.Cu" "F.Mask" "F.Paste")
			(net "GND")
		)
		(pad "G1" smd rect
			(at 2.975102 -10.349992 270)
			(size 1.2446 2.794)
			(layers "F.Cu" "F.Mask" "F.Paste")
			(net "GND")
		)
		(pad "G2" smd rect
			(at 2.975102 10.349992 270)
			(size 1.2446 2.794)
			(layers "F.Cu" "F.Mask" "F.Paste")
			(net "GND")
		)
	)
)
